FILE_TYPE = CONNECTIVITY;
{Allegro Design Entry HDL 17.2-2016 S081 (4005846) 1/11/2022}
"PAGE_NUMBER" = 187;
0"NC";
1"GND\g";
2"GND\g";
3"GND\g";
4"GND\g";
5"GND\g";
6"GND\g";
7"GND\g";
8"GND\g";
9"GND\g";
10"GND\g";
11"SW_PVDDCR_CPU0_P1_PH4";
12"SW_PVDDCR_CPU0_P1_PH3";
13"SW_PVDDCR_CPU0_P1_SW3";
14"SW_PVDDCR_CPU0_P1_BOOT3";
15"PVDDCR_CPU0_P1_VCCS";
16"PVDDCR_CPU0_P1_PWM4";
17"NC_PVDDCR_CPU0_P1_DNC4";
18"PVDDCR_CPU0_P1_VCC4";
19"PVDDCR_CPU0_P1_LSET4";
20"PVDDCR_CPU0_P1_TEMP0";
21"PVDDCR_CPU0_P1_IMON4";
22"PVDDCR_CPU0_P1_PVCC\g";
23"GND\g";
24"NC_PVDDCR_CPU0_P1_GL2_4";
25"NC_PVDDCR_CPU0_P1_GL1_4";
26"SW_PVDDCR_CPU0_P1_BOOT4";
27"PVDDCR_CPU0_P1_VOS4";
28"SW_PVDDCR_CPU0_P1_SW4_RC";
29"SW_P12V_STBY_PVDDCR_CPU0_P1_FLT\g";
30"GND\g";
31"PVDDCR_CPU0_P1_VOS3";
32"PVDDCR_CPU0_P1_VCCS";
33"PVDDCR_CPU0_P1_VCC3";
34"NC_PVDDCR_CPU0_P1_DNC3";
35"PVDDCR_CPU0_P1_LSET3";
36"PVDDCR_CPU0_P1_IMON3";
37"PVDDCR_CPU0_P1_TEMP0";
38"PVDDCR_CPU0_P1_PWM3";
39"PVDDCR_CPU0_P1_PVCC\g";
40"GND\g";
41"SW_P12V_STBY_PVDDCR_CPU0_P1_FLT\g";
42"NC_PVDDCR_CPU0_P1_GL1_3";
43"NC_PVDDCR_CPU0_P1_GL2_3";
44"GND\g";
45"SW_PVDDCR_CPU0_P1_SW3_RC";
46"SW_PVDDCR_CPU0_P1_SW4";
47"SW_PVDDCR_CPU0_P1_BOOT4_RC";
48"IND_CPU0_P1_CPL3";
49"PVDDCR_CPU0_P1\g";
50"GND\g";
51"GND\g";
52"PVDDCR_CPU0_P1\g";
53"SW_PVDDCR_CPU0_P1_BOOT3_RC";
54"IND_CPU0_P1_CPL2";
55"IND_CPU0_P1_CPL3";
56"GND\g";
%"UNIVERSAL_GND"
"1","(-7775,4350)","0","pure_quanta_power","I1";
;
CDS_LIB"pure_quanta_power"
HDL_POWER"GND";
"A"1;
%"UNIVERSAL_GND"
"1","(-7375,1125)","0","pure_quanta_power","I102";
;
CDS_LIB"pure_quanta_power"
HDL_POWER"GND";
"A"2;
%"Q_CAP"
"1","(-7700,1325)","0","pure_quanta","I105";
;
LOCATION"PC285_4"
$SEC"1"
CDS_SEC"1"
MATERIAL"X7R"
TOLERANCE"10%"
VALUE"0.1UF"
PART_NUMBER"CH4104K1B00"
VOLTAGE"25V"
PACK_TYPE"0402"
CDS_LIB"pure_quanta";
"B"
$PN"2"3;
"A"
$PN"1"15;
%"UNIVERSAL_GND"
"1","(-7700,1050)","0","pure_quanta_power","I106";
;
CDS_LIB"pure_quanta_power"
HDL_POWER"GND";
"A"3;
%"Q_CAP"
"1","(-5325,5800)","0","pure_quanta","I107";
;
LOCATION"PC290_3"
$SEC"1"
CDS_SEC"1"
MATERIAL"X7R"
TOLERANCE"10%"
VALUE"0.1UF"
PART_NUMBER"CH4104K1B00"
VOLTAGE"25V"
PACK_TYPE"0402"
CDS_LIB"pure_quanta";
"B"
$PN"2"44;
"A"
$PN"1"41;
%"Q_CAP"
"1","(-5200,2500)","0","pure_quanta","I108";
;
LOCATION"PC291_4"
$SEC"1"
CDS_SEC"1"
MATERIAL"X7R"
TOLERANCE"10%"
VALUE"0.1UF"
PART_NUMBER"CH4104K1B00"
VOLTAGE"25V"
PACK_TYPE"0402"
CDS_LIB"pure_quanta";
"B"
$PN"2"30;
"A"
$PN"1"29;
%"Q_CAP"
"1","(-7450,5250)","0","pure_quanta","I109";
;
LOCATION"PC286"
$SEC"1"
CDS_SEC"1"
MATERIAL"X6S"
TOLERANCE"10%"
VALUE"2.2UF"
PART_NUMBER"CH5222KEB01"
VOLTAGE"10V"
PACK_TYPE"C0402"
CDS_LIB"pure_quanta";
"B"
$PN"2"4;
"A"
$PN"1"33;
%"UNIVERSAL_GND"
"1","(-7450,5050)","0","pure_quanta_power","I110";
;
CDS_LIB"pure_quanta_power"
HDL_POWER"GND";
"A"4;
%"UNIVERSAL_GND"
"1","(-7100,5550)","0","pure_quanta_power","I111";
;
CDS_LIB"pure_quanta_power"
HDL_POWER"GND";
"A"5;
%"Q_RES"
"2","(-7450,5800)","0","pure_quanta","I112";
;
LOCATION"PR193"
$SEC"1"
CDS_SEC"1"
WATTAGE"1/16W"
MATERIAL"CHIP"
TOLERANCE"1%"
VALUE"2.2"
PART_NUMBER"CS-2202FB00"
PACK_TYPE"0402LF"
CDS_LIB"pure_quanta";
"A"
$PN"1"39;
"B"
$PN"2"33;
%"Q_CAP"
"1","(-7100,5825)","0","pure_quanta","I113";
;
LOCATION"PC288_C0P1_3"
$SEC"1"
CDS_SEC"1"
MATERIAL"X6S"
TOLERANCE"10%"
VALUE"2.2UF"
PART_NUMBER"CH5222KEB01"
VOLTAGE"10V"
PACK_TYPE"C0402"
CDS_LIB"pure_quanta";
"B"
$PN"2"5;
"A"
$PN"1"39;
%"VCC_CORE"
"1","(-7450,6200)","0","pure_quanta_power","I114";
;
HDL_POWER"PVDDCR_CPU0_P1_PVCC"
CDS_LIB"pure_quanta_power";
"A"39;
%"Q_CAP"
"1","(-7350,1950)","0","pure_quanta","I115";
;
LOCATION"PC287"
$SEC"1"
CDS_SEC"1"
MATERIAL"X6S"
TOLERANCE"10%"
VALUE"2.2UF"
PART_NUMBER"CH5222KEB01"
VOLTAGE"10V"
PACK_TYPE"C0402"
CDS_LIB"pure_quanta";
"B"
$PN"2"6;
"A"
$PN"1"18;
%"UNIVERSAL_GND"
"1","(-7350,1750)","0","pure_quanta_power","I116";
;
CDS_LIB"pure_quanta_power"
HDL_POWER"GND";
"A"6;
%"UNIVERSAL_GND"
"1","(-7000,2250)","0","pure_quanta_power","I117";
;
CDS_LIB"pure_quanta_power"
HDL_POWER"GND";
"A"7;
%"Q_RES"
"2","(-7350,2500)","0","pure_quanta","I118";
;
LOCATION"PR194"
$SEC"1"
CDS_SEC"1"
WATTAGE"1/16W"
MATERIAL"CHIP"
TOLERANCE"1%"
VALUE"2.2"
PART_NUMBER"CS-2202FB00"
PACK_TYPE"0402LF"
CDS_LIB"pure_quanta";
"A"
$PN"1"22;
"B"
$PN"2"18;
%"Q_CAP"
"1","(-7000,2525)","0","pure_quanta","I119";
;
LOCATION"PC289_C0P1_4"
$SEC"1"
CDS_SEC"1"
MATERIAL"X6S"
TOLERANCE"10%"
VALUE"2.2UF"
PART_NUMBER"CH5222KEB01"
VOLTAGE"10V"
PACK_TYPE"C0402"
CDS_LIB"pure_quanta";
"B"
$PN"2"7;
"A"
$PN"1"22;
%"VCC_CORE"
"1","(-7350,2900)","0","pure_quanta_power","I120";
;
HDL_POWER"PVDDCR_CPU0_P1_PVCC"
CDS_LIB"pure_quanta_power";
"A"22;
%"UNIVERSAL_GND"
"1","(-4450,3975)","0","pure_quanta_power","I121";
;
CDS_LIB"pure_quanta_power"
HDL_POWER"GND";
"A"8;
%"Q_RES"
"2","(-4450,4200)","0","pure_quanta","I122";
;
LOCATION"PR522"
$SEC"1"
CDS_SEC"1"
WATTAGE"1/8W"
MATERIAL"EMPTY"
TOLERANCE"1%"
VALUE"1.5"
PART_NUMBER"CS-1504FB00"
PACK_TYPE"0402LF"
CDS_LIB"pure_quanta";
"A"
$PN"1"45;
"B"
$PN"2"8;
%"Q_CAP"
"1","(-4450,4700)","0","pure_quanta","I123";
;
LOCATION"PC316"
$SEC"1"
CDS_SEC"1"
MATERIAL"EMPTY"
TOLERANCE"10%"
VALUE"560PF"
PART_NUMBER"CH1566K1B09"
VOLTAGE"50V"
PACK_TYPE"C0402"
CDS_LIB"pure_quanta";
"B"
$PN"2"45;
"A"
$PN"1"13;
%"UNIVERSAL_GND"
"1","(-4450,675)","0","pure_quanta_power","I124";
;
CDS_LIB"pure_quanta_power"
HDL_POWER"GND";
"A"9;
%"Q_RES"
"2","(-4450,900)","0","pure_quanta","I125";
;
LOCATION"PR523"
$SEC"1"
CDS_SEC"1"
WATTAGE"1/8W"
MATERIAL"EMPTY"
TOLERANCE"1%"
VALUE"1.5"
PART_NUMBER"CS-1504FB00"
PACK_TYPE"0402LF"
CDS_LIB"pure_quanta";
"A"
$PN"1"28;
"B"
$PN"2"9;
%"Q_CAP"
"1","(-4450,1400)","0","pure_quanta","I126";
;
LOCATION"PC317"
$SEC"1"
CDS_SEC"1"
MATERIAL"EMPTY"
TOLERANCE"10%"
VALUE"560PF"
PART_NUMBER"CH1566K1B09"
VOLTAGE"50V"
PACK_TYPE"C0402"
CDS_LIB"pure_quanta";
"B"
$PN"2"28;
"A"
$PN"1"46;
%"UNIVERSAL_GND"
"1","(-1725,1225)","0","pure_quanta_power","I127";
;
CDS_LIB"pure_quanta_power"
HDL_POWER"GND";
"A"50;
%"UNIVERSAL_GND"
"1","(-5400,4125)","0","pure_quanta_power","I15";
;
CDS_LIB"pure_quanta_power"
HDL_POWER"GND";
"A"40;
%"Q_RES"
"1","(-4175,3800)","0","pure_quanta","I16";
;
LOCATION"PR199"
$SEC"1"
CDS_SEC"1"
WATTAGE"1/16W"
MATERIAL"CHIP"
TOLERANCE"5%"
VALUE"0"
PART_NUMBER"CS00002JB38"
PACK_TYPE"0402LF"
CDS_LIB"pure_quanta";
"B"
$PN"2"52;
"A"
$PN"1"31;
%"Q_RES"
"1","(-4575,5250)","0","pure_quanta","I18";
;
LOCATION"PR197"
$SEC"1"
CDS_SEC"1"
PACK_TYPE"0402LF"
TOLERANCE"1%"
MATERIAL"CHIP"
WATTAGE"1/16W"
VALUE"4.7"
PART_NUMBER"CS-4702FB19"
CDS_LIB"pure_quanta";
"B"
$PN"2"53;
"A"
$PN"1"14;
%"Q_CAP"
"1","(-4975,5800)","0","pure_quanta","I19";
;
LOCATION"PC292_3"
$SEC"1"
CDS_SEC"1"
MATERIAL"X6S"
TOLERANCE"10%"
VALUE"1UF"
PART_NUMBER"CH5104KEB02"
VOLTAGE"25V"
PACK_TYPE"C0402"
CDS_LIB"pure_quanta";
"B"
$PN"2"44;
"A"
$PN"1"41;
%"Q_CAP"
"1","(-4650,5800)","0","pure_quanta","I20";
;
LOCATION"PC294_3"
$SEC"1"
CDS_SEC"1"
MATERIAL"X6S"
TOLERANCE"10%"
VALUE"10UF"
PART_NUMBER"CH6104KEA00"
VOLTAGE"25V"
PACK_TYPE"C0805"
CDS_LIB"pure_quanta";
"B"
$PN"2"44;
"A"
$PN"1"41;
%"Q_CAP"
"1","(-4325,5800)","0","pure_quanta","I21";
;
LOCATION"PC296_3"
$SEC"1"
CDS_SEC"1"
MATERIAL"X6S"
TOLERANCE"10%"
VALUE"10UF"
PART_NUMBER"CH6104KEA00"
VOLTAGE"25V"
PACK_TYPE"C0805"
CDS_LIB"pure_quanta";
"B"
$PN"2"44;
"A"
$PN"1"41;
%"Q_INDUCTOR4P_14"
"1","(-2650,4775)","0","pure_quanta","I23";
;
LOCATION"PL31"
$SEC"1"
CDS_SEC"1"
PART_TYPE"SMLF"
MATERIAL"IND"
VALUE"150NH"
PART_NUMBER"CV+15^0TZ04"
CDS_LIB"pure_quanta"
NEEDS_NO_SIZE"TRUE";
"1"
$PN"1"13;
"4"
$PN"4"52;
"3"
$PN"3"55;
"2"
$PN"2"54;
%"Q_CAP"
"1","(-3600,5125)","0","pure_quanta","I26";
;
LOCATION"PC300"
$SEC"1"
CDS_SEC"1"
MATERIAL"X7R"
TOLERANCE"10%"
VALUE"0.22UF"
PART_NUMBER"CH4223K1B00"
VOLTAGE"16V"
PACK_TYPE"0402"
CDS_LIB"pure_quanta";
"B"
$PN"2"12;
"A"
$PN"1"53;
%"UNIVERSAL_GND"
"1","(-4025,5475)","0","pure_quanta_power","I27";
;
CDS_LIB"pure_quanta_power"
HDL_POWER"GND";
"A"44;
%"Q_CAP"
"1","(-4025,5800)","0","pure_quanta","I28";
;
LOCATION"PC298_3"
$SEC"1"
CDS_SEC"1"
MATERIAL"X6S"
TOLERANCE"10%"
VALUE"10UF"
PART_NUMBER"CH6104KEA00"
VOLTAGE"25V"
PACK_TYPE"C0805"
CDS_LIB"pure_quanta";
"B"
$PN"2"44;
"A"
$PN"1"41;
%"VCC_CORE"
"1","(-4025,6100)","0","pure_quanta_power","I29";
;
HDL_POWER"SW_P12V_STBY_PVDDCR_CPU0_P1_FLT"
CDS_LIB"pure_quanta_power";
"A"41;
%"Q_CAP"
"1","(-7775,4625)","0","pure_quanta","I3";
;
LOCATION"PC284_3"
$SEC"1"
CDS_SEC"1"
MATERIAL"X7R"
TOLERANCE"10%"
VALUE"0.1UF"
PART_NUMBER"CH4104K1B00"
VOLTAGE"25V"
PACK_TYPE"0402"
CDS_LIB"pure_quanta";
"B"
$PN"2"1;
"A"
$PN"1"32;
%"Q_CAP"
"1","(-1250,4725)","0","pure_quanta","I31";
;
LOCATION"PC302_3"
$SEC"1"
CDS_SEC"1"
MATERIAL"X6S"
TOLERANCE"20%"
VALUE"22UF"
PART_NUMBER"TMP_QCH622KMEA01"
VOLTAGE"4V"
PACK_TYPE"0805"
CDS_LIB"pure_quanta";
"B"
$PN"2"56;
"A"
$PN"1"52;
%"UNIVERSAL_GND"
"1","(-825,4375)","0","pure_quanta_power","I32";
;
CDS_LIB"pure_quanta_power"
HDL_POWER"GND";
"A"56;
%"Q_CAP"
"1","(-825,4725)","0","pure_quanta","I33";
;
LOCATION"PC304_3"
$SEC"1"
CDS_SEC"1"
MATERIAL"X6S"
TOLERANCE"20%"
VALUE"22UF"
PART_NUMBER"TMP_QCH622KMEA01"
VOLTAGE"4V"
PACK_TYPE"0805"
CDS_LIB"pure_quanta";
"B"
$PN"2"56;
"A"
$PN"1"52;
%"VCC_CORE"
"1","(-825,5050)","0","pure_quanta_power","I34";
;
HDL_POWER"PVDDCR_CPU0_P1"
CDS_LIB"pure_quanta_power";
"A"52;
%"ISL99390FRZTR5935"
"1","(-5950,4900)","0","pure_quanta","I35";
;
LOCATION"PU27"
$SEC"1"
CDS_SEC"1"
PART_TYPE"SMLF"
MATERIAL"IC"
VALUE"ISL99390FRZ-TR5935"
PART_NUMBER"AL099390004"
CDS_LIB"pure_quanta"
NEEDS_NO_SIZE"TRUE"
CDS_LMAN_SYM_OUTLINE"-300,700,250,-650";
"PGND2"
$PN"7_9-20_24"40;
"GL2"
$PN"41"43;
"GL1"
$PN"6"42;
"DNC"
$PN"31"34;
"EN"
$PN"35"33;
"PGND3"
$PN"40"40;
"VOS"
$PN"1"31;
"VIN2"
$PN"30"41;
"PGND1"
$PN"5"40;
"SW"
$PN"10_19"13;
"LSET"
$PN"37"35;
"IOUT"
$PN"38"36;
"TOUT_FLT"
$PN"36"37;
"PVCC"
$PN"4"39;
"PHASE"
$PN"32"12;
"VIN1"
$PN"25_29"41;
"BOOT"
$PN"33"14;
"AGND"
$PN"2"40;
"VCC"
$PN"3"33;
"REFIN"
$PN"39"32;
"PWM"
$PN"34"38;
%"UNIVERSAL_GND"
"1","(-7475,4425)","0","pure_quanta_power","I4";
;
CDS_LIB"pure_quanta_power"
HDL_POWER"GND";
"A"10;
%"ISL99390FRZTR5935"
"1","(-5875,1600)","0","pure_quanta","I72";
;
LOCATION"PU28"
$SEC"1"
CDS_SEC"1"
PART_TYPE"SMLF"
MATERIAL"IC"
VALUE"ISL99390FRZ-TR5935"
PART_NUMBER"AL099390004"
CDS_LIB"pure_quanta"
CDS_LMAN_SYM_OUTLINE"-300,700,250,-650"
NEEDS_NO_SIZE"TRUE";
"PGND2"
$PN"7_9-20_24"23;
"GL2"
$PN"41"24;
"GL1"
$PN"6"25;
"DNC"
$PN"31"17;
"EN"
$PN"35"18;
"PGND3"
$PN"40"23;
"VOS"
$PN"1"27;
"VIN2"
$PN"30"29;
"PGND1"
$PN"5"23;
"SW"
$PN"10_19"46;
"LSET"
$PN"37"19;
"IOUT"
$PN"38"21;
"TOUT_FLT"
$PN"36"20;
"PVCC"
$PN"4"22;
"PHASE"
$PN"32"11;
"VIN1"
$PN"25_29"29;
"BOOT"
$PN"33"26;
"AGND"
$PN"2"23;
"VCC"
$PN"3"18;
"REFIN"
$PN"39"15;
"PWM"
$PN"34"16;
%"VCC_CORE"
"1","(-775,1750)","0","pure_quanta_power","I74";
;
HDL_POWER"PVDDCR_CPU0_P1"
CDS_LIB"pure_quanta_power";
"A"49;
%"Q_CAP"
"1","(-775,1425)","0","pure_quanta","I75";
;
LOCATION"PC305_4"
$SEC"1"
CDS_SEC"1"
MATERIAL"X6S"
TOLERANCE"20%"
VALUE"22UF"
PART_NUMBER"TMP_QCH622KMEA01"
VOLTAGE"4V"
PACK_TYPE"0805"
CDS_LIB"pure_quanta";
"B"
$PN"2"51;
"A"
$PN"1"49;
%"UNIVERSAL_GND"
"1","(-775,1075)","0","pure_quanta_power","I76";
;
CDS_LIB"pure_quanta_power"
HDL_POWER"GND";
"A"51;
%"Q_CAP"
"1","(-1200,1425)","0","pure_quanta","I77";
;
LOCATION"PC303_4"
$SEC"1"
CDS_SEC"1"
MATERIAL"X6S"
TOLERANCE"20%"
VALUE"22UF"
PART_NUMBER"TMP_QCH622KMEA01"
VOLTAGE"4V"
PACK_TYPE"0805"
CDS_LIB"pure_quanta";
"B"
$PN"2"51;
"A"
$PN"1"49;
%"Q_RES"
"1","(-7150,4600)","0","pure_quanta","I8";
;
LOCATION"PR195"
$SEC"1"
CDS_SEC"1"
WATTAGE"1/16W"
MATERIAL"EMPTY"
TOLERANCE"1%"
VALUE"8.87K"
PART_NUMBER"CS28872FB01"
PACK_TYPE"0402LF"
CDS_LIB"pure_quanta";
"B"
$PN"2"35;
"A"
$PN"1"10;
%"VCC_CORE"
"1","(-3875,2800)","0","pure_quanta_power","I81";
;
HDL_POWER"SW_P12V_STBY_PVDDCR_CPU0_P1_FLT"
CDS_LIB"pure_quanta_power";
"A"29;
%"Q_CAP"
"1","(-3875,2500)","0","pure_quanta","I82";
;
LOCATION"PC299_4"
$SEC"1"
CDS_SEC"1"
MATERIAL"X6S"
TOLERANCE"10%"
VALUE"10UF"
PART_NUMBER"CH6104KEA00"
VOLTAGE"25V"
PACK_TYPE"C0805"
CDS_LIB"pure_quanta";
"B"
$PN"2"30;
"A"
$PN"1"29;
%"UNIVERSAL_GND"
"1","(-3875,2150)","0","pure_quanta_power","I83";
;
CDS_LIB"pure_quanta_power"
HDL_POWER"GND";
"A"30;
%"Q_INDUCTOR4P_14"
"1","(-2550,1475)","0","pure_quanta","I84";
;
LOCATION"PL32"
$SEC"1"
CDS_SEC"1"
PART_TYPE"SMLF"
MATERIAL"IND"
VALUE"150NH"
PART_NUMBER"CV+15^0TZ04"
NEEDS_NO_SIZE"TRUE"
CDS_LIB"pure_quanta";
"1"
$PN"1"46;
"4"
$PN"4"49;
"3"
$PN"3"50;
"2"
$PN"2"48;
%"Q_CAP"
"1","(-3525,1825)","0","pure_quanta","I85";
;
LOCATION"PC301"
$SEC"1"
CDS_SEC"1"
MATERIAL"X7R"
TOLERANCE"10%"
VALUE"0.22UF"
PART_NUMBER"CH4223K1B00"
VOLTAGE"16V"
PACK_TYPE"0402"
CDS_LIB"pure_quanta";
"B"
$PN"2"11;
"A"
$PN"1"47;
%"Q_CAP"
"1","(-4175,2500)","0","pure_quanta","I86";
;
LOCATION"PC297_4"
$SEC"1"
CDS_SEC"1"
MATERIAL"X6S"
TOLERANCE"10%"
VALUE"10UF"
PART_NUMBER"CH6104KEA00"
VOLTAGE"25V"
PACK_TYPE"C0805"
CDS_LIB"pure_quanta";
"B"
$PN"2"30;
"A"
$PN"1"29;
%"Q_CAP"
"1","(-4500,2500)","0","pure_quanta","I87";
;
LOCATION"PC295_4"
$SEC"1"
CDS_SEC"1"
MATERIAL"X6S"
TOLERANCE"10%"
VALUE"10UF"
PART_NUMBER"CH6104KEA00"
VOLTAGE"25V"
PACK_TYPE"C0805"
CDS_LIB"pure_quanta";
"B"
$PN"2"30;
"A"
$PN"1"29;
%"Q_CAP"
"1","(-4825,2500)","0","pure_quanta","I88";
;
LOCATION"PC293_4"
$SEC"1"
CDS_SEC"1"
MATERIAL"X6S"
TOLERANCE"10%"
VALUE"1UF"
PART_NUMBER"CH5104KEB02"
VOLTAGE"25V"
PACK_TYPE"C0402"
CDS_LIB"pure_quanta";
"B"
$PN"2"30;
"A"
$PN"1"29;
%"Q_RES"
"1","(-4500,1950)","0","pure_quanta","I89";
;
LOCATION"PR198"
$SEC"1"
CDS_SEC"1"
PACK_TYPE"0402LF"
TOLERANCE"1%"
MATERIAL"CHIP"
WATTAGE"1/16W"
VALUE"4.7"
PART_NUMBER"CS-4702FB19"
CDS_LIB"pure_quanta";
"B"
$PN"2"47;
"A"
$PN"1"26;
%"Q_RES"
"1","(-4125,500)","0","pure_quanta","I90";
;
LOCATION"PR200"
$SEC"1"
CDS_SEC"1"
WATTAGE"1/16W"
MATERIAL"CHIP"
TOLERANCE"5%"
VALUE"0"
PART_NUMBER"CS00002JB38"
PACK_TYPE"0402LF"
CDS_LIB"pure_quanta";
"B"
$PN"2"49;
"A"
$PN"1"27;
%"UNIVERSAL_GND"
"1","(-5325,850)","0","pure_quanta_power","I92";
;
CDS_LIB"pure_quanta_power"
HDL_POWER"GND";
"A"23;
%"Q_RES"
"1","(-7050,1300)","0","pure_quanta","I96";
;
LOCATION"PR196"
$SEC"1"
CDS_SEC"1"
WATTAGE"1/16W"
MATERIAL"EMPTY"
TOLERANCE"1%"
VALUE"8.87K"
PART_NUMBER"CS28872FB01"
PACK_TYPE"0402LF"
CDS_LIB"pure_quanta";
"B"
$PN"2"19;
"A"
$PN"1"2;
END.
